(kicad_pcb
	(version 20260206)
	(generator "pcbnew")
	(generator_version "10.0")
	(general
		(thickness 1.6)
		(legacy_teardrops no)
	)
	(paper "A4")
	(title_block
		(title "15969-1a.1015WZS0858.brd")
		(comment 1 "Tioga Pass / footprint 150 of 295 (SLOT3), pads 77-151 of 166")
	)
	(layers
		(0 "F.Cu" signal "TOP")
		(4 "In1.Cu" signal "L2GND")
		(6 "In2.Cu" signal "L3")
		(8 "In3.Cu" signal "L4")
		(10 "In4.Cu" signal "L5GND")
		(2 "B.Cu" signal "BOTTOM")
		(9 "F.Adhes" user "F.Adhesive")
		(11 "B.Adhes" user "B.Adhesive")
		(13 "F.Paste" user "Package Geometry/Pastemask Top")
		(15 "B.Paste" user "Package Geometry/Pastemask Bottom")
		(5 "F.SilkS" user "Ref Des/Silkscreen Top")
		(7 "B.SilkS" user "Ref Des/Silkscreen Bottom")
		(1 "F.Mask" user "Board Geometry/Soldermask Top")
		(3 "B.Mask" user "Board Geometry/Soldermask Bottom")
		(17 "Dwgs.User" user "User.Drawings")
		(19 "Cmts.User" user "User.Comments")
		(21 "Eco1.User" user "User.Eco1")
		(23 "Eco2.User" user "User.Eco2")
		(25 "Edge.Cuts" user "Board Geometry/Outline")
		(27 "Margin" user)
		(31 "F.CrtYd" user "Package Geometry/Place Bound Top")
		(29 "B.CrtYd" user "Package Geometry/Place Bound Bottom")
		(35 "F.Fab" user "Ref Des/Assembly Top")
		(33 "B.Fab" user "Ref Des/Assembly Bottom")
	)
	(footprint ""
		(layer "F.Cu")
		(at 42.729912 -30.820106)
		(property "Reference" "SLOT3"
			(at 0 0 0)
			(layer "F.SilkS")
			(hide yes)
			(effects
				(font
					(size 1.27 1.27)
				)
			)
		)
		(property "Value" "PCISLT164-129-GP"
			(at -15.9639 4.8514 0)
			(unlocked yes)
			(layer "F.Fab")
			(hide yes)
			(effects
				(font
					(size 1.016 1.016)
					(thickness 0.1524)
				)
			)
		)
		(property "Device Type" "10018783-10203TLF"
			(at -15.9639 3.3274 0)
			(unlocked yes)
			(layer "F.Fab")
			(hide yes)
			(effects
				(font
					(size 1.016 1.016)
					(thickness 0.1524)
				)
			)
		)
		(duplicate_pad_numbers_are_jumpers no)
		(pad "A75" thru_hole circle
			(at 64.34963 -1.24968)
			(size 1.0668 1.0668)
			(drill 0.7112)
			(layers "*.Cu" "*.Mask")
			(remove_unused_layers no)
			(net "GND")
			(clearance 0.1778)
			(thermal_gap 0.1778)
		)
		(pad "A76" thru_hole circle
			(at 65.35039 -3.24993)
			(size 1.0668 1.0668)
			(drill 0.7112)
			(layers "*.Cu" "*.Mask")
			(remove_unused_layers no)
			(net "P3E_CPU0_PE2_SS_RXP<14>")
			(clearance 0.1778)
			(thermal_gap 0.1778)
		)
		(pad "A77" thru_hole circle
			(at 66.34988 -1.24968)
			(size 1.0668 1.0668)
			(drill 0.7112)
			(layers "*.Cu" "*.Mask")
			(remove_unused_layers no)
			(net "P3E_CPU0_PE2_SS_RXN<14>")
			(clearance 0.1778)
			(thermal_gap 0.1778)
		)
		(pad "A78" thru_hole circle
			(at 67.34937 -3.24993)
			(size 1.0668 1.0668)
			(drill 0.7112)
			(layers "*.Cu" "*.Mask")
			(remove_unused_layers no)
			(net "GND")
			(clearance 0.1778)
			(thermal_gap 0.1778)
		)
		(pad "A79" thru_hole circle
			(at 68.35013 -1.24968)
			(size 1.0668 1.0668)
			(drill 0.7112)
			(layers "*.Cu" "*.Mask")
			(remove_unused_layers no)
			(net "GND")
			(clearance 0.1778)
			(thermal_gap 0.1778)
		)
		(pad "A80" thru_hole circle
			(at 69.34962 -3.24993)
			(size 1.0668 1.0668)
			(drill 0.7112)
			(layers "*.Cu" "*.Mask")
			(remove_unused_layers no)
			(net "P3E_CPU0_PE2_SS_RXP<15>")
			(clearance 0.1778)
			(thermal_gap 0.1778)
		)
		(pad "A81" thru_hole circle
			(at 70.35038 -1.24968)
			(size 1.0668 1.0668)
			(drill 0.7112)
			(layers "*.Cu" "*.Mask")
			(remove_unused_layers no)
			(net "P3E_CPU0_PE2_SS_RXN<15>")
			(clearance 0.1778)
			(thermal_gap 0.1778)
		)
		(pad "A82" thru_hole circle
			(at 71.34987 -3.24993)
			(size 1.0668 1.0668)
			(drill 0.7112)
			(layers "*.Cu" "*.Mask")
			(remove_unused_layers no)
			(net "GND")
			(clearance 0.1778)
			(thermal_gap 0.1778)
		)
		(pad "B1" thru_hole circle
			(at -11.64971 1.24968)
			(size 1.0668 1.0668)
			(drill 0.7112)
			(layers "*.Cu" "*.Mask")
			(remove_unused_layers no)
			(net "P12V_SLOT3")
			(clearance 0.1778)
			(thermal_gap 0.1778)
		)
		(pad "B2" thru_hole circle
			(at -10.65022 3.24993)
			(size 1.0668 1.0668)
			(drill 0.7112)
			(layers "*.Cu" "*.Mask")
			(remove_unused_layers no)
			(net "P12V_SLOT3")
			(clearance 0.1778)
			(thermal_gap 0.1778)
		)
		(pad "B3" thru_hole circle
			(at -9.64946 1.24968)
			(size 1.0668 1.0668)
			(drill 0.7112)
			(layers "*.Cu" "*.Mask")
			(remove_unused_layers no)
			(net "P12V_SLOT3")
			(clearance 0.1778)
			(thermal_gap 0.1778)
		)
		(pad "B4" thru_hole circle
			(at -8.64997 3.24993)
			(size 1.0668 1.0668)
			(drill 0.7112)
			(layers "*.Cu" "*.Mask")
			(remove_unused_layers no)
			(net "GND")
			(clearance 0.1778)
			(thermal_gap 0.1778)
		)
		(pad "B5" thru_hole circle
			(at -7.65048 1.24968)
			(size 1.0668 1.0668)
			(drill 0.7112)
			(layers "*.Cu" "*.Mask")
			(remove_unused_layers no)
			(net "SMCLK_BMC_SLOT3_R")
			(clearance 0.1778)
			(thermal_gap 0.1778)
		)
		(pad "B6" thru_hole circle
			(at -6.64972 3.24993)
			(size 1.0668 1.0668)
			(drill 0.7112)
			(layers "*.Cu" "*.Mask")
			(remove_unused_layers no)
			(net "SMDAT_BMC_SLOT3_R")
			(clearance 0.1778)
			(thermal_gap 0.1778)
		)
		(pad "B7" thru_hole circle
			(at -5.65023 1.24968)
			(size 1.0668 1.0668)
			(drill 0.7112)
			(layers "*.Cu" "*.Mask")
			(remove_unused_layers no)
			(net "GND")
			(clearance 0.1778)
			(thermal_gap 0.1778)
		)
		(pad "B8" thru_hole circle
			(at -4.64947 3.24993)
			(size 1.0668 1.0668)
			(drill 0.7112)
			(layers "*.Cu" "*.Mask")
			(remove_unused_layers no)
			(net "P3V3")
			(clearance 0.1778)
			(thermal_gap 0.1778)
		)
		(pad "B9" thru_hole circle
			(at -3.64998 1.24968)
			(size 1.0668 1.0668)
			(drill 0.7112)
			(layers "*.Cu" "*.Mask")
			(remove_unused_layers no)
			(net "Net_94")
			(clearance 0.1778)
			(thermal_gap 0.1778)
		)
		(pad "B10" thru_hole circle
			(at -2.65049 3.24993)
			(size 1.0668 1.0668)
			(drill 0.7112)
			(layers "*.Cu" "*.Mask")
			(remove_unused_layers no)
			(net "P3V3_STBY")
			(clearance 0.1778)
			(thermal_gap 0.1778)
		)
		(pad "B11" thru_hole circle
			(at -1.64973 1.24968)
			(size 1.0668 1.0668)
			(drill 0.7112)
			(layers "*.Cu" "*.Mask")
			(remove_unused_layers no)
			(net "FM_PE_SLOTX24_WAKE_N")
			(clearance 0.1778)
			(thermal_gap 0.1778)
		)
		(pad "B12" thru_hole circle
			(at 1.35001 3.24993)
			(size 1.0668 1.0668)
			(drill 0.7112)
			(layers "*.Cu" "*.Mask")
			(remove_unused_layers no)
			(net "SMB_ALERT_S3_B12_N")
			(clearance 0.1778)
			(thermal_gap 0.1778)
		)
		(pad "B13" thru_hole circle
			(at 2.3495 1.24968)
			(size 1.0668 1.0668)
			(drill 0.7112)
			(layers "*.Cu" "*.Mask")
			(remove_unused_layers no)
			(net "GND")
			(clearance 0.1778)
			(thermal_gap 0.1778)
		)
		(pad "B14" thru_hole circle
			(at 3.35026 3.24993)
			(size 1.0668 1.0668)
			(drill 0.7112)
			(layers "*.Cu" "*.Mask")
			(remove_unused_layers no)
			(net "P3E_CPU0_PE2_SS_C_TXP<0>")
			(clearance 0.1778)
			(thermal_gap 0.1778)
		)
		(pad "B15" thru_hole circle
			(at 4.34975 1.24968)
			(size 1.0668 1.0668)
			(drill 0.7112)
			(layers "*.Cu" "*.Mask")
			(remove_unused_layers no)
			(net "P3E_CPU0_PE2_SS_C_TXN<0>")
			(clearance 0.1778)
			(thermal_gap 0.1778)
		)
		(pad "B16" thru_hole circle
			(at 5.35051 3.24993)
			(size 1.0668 1.0668)
			(drill 0.7112)
			(layers "*.Cu" "*.Mask")
			(remove_unused_layers no)
			(net "GND")
			(clearance 0.1778)
			(thermal_gap 0.1778)
		)
		(pad "B17" thru_hole circle
			(at 6.35 1.24968)
			(size 1.0668 1.0668)
			(drill 0.7112)
			(layers "*.Cu" "*.Mask")
			(remove_unused_layers no)
			(net "PCIE_SLOT3_PRSNT2_1_N")
			(clearance 0.1778)
			(thermal_gap 0.1778)
		)
		(pad "B18" thru_hole circle
			(at 7.34949 3.24993)
			(size 1.0668 1.0668)
			(drill 0.7112)
			(layers "*.Cu" "*.Mask")
			(remove_unused_layers no)
			(net "GND")
			(clearance 0.1778)
			(thermal_gap 0.1778)
		)
		(pad "B19" thru_hole circle
			(at 8.35025 1.24968)
			(size 1.0668 1.0668)
			(drill 0.7112)
			(layers "*.Cu" "*.Mask")
			(remove_unused_layers no)
			(net "P3E_CPU0_PE2_SS_C_TXP<1>")
			(clearance 0.1778)
			(thermal_gap 0.1778)
		)
		(pad "B20" thru_hole circle
			(at 9.34974 3.24993)
			(size 1.0668 1.0668)
			(drill 0.7112)
			(layers "*.Cu" "*.Mask")
			(remove_unused_layers no)
			(net "P3E_CPU0_PE2_SS_C_TXN<1>")
			(clearance 0.1778)
			(thermal_gap 0.1778)
		)
		(pad "B21" thru_hole circle
			(at 10.3505 1.24968)
			(size 1.0668 1.0668)
			(drill 0.7112)
			(layers "*.Cu" "*.Mask")
			(remove_unused_layers no)
			(net "GND")
			(clearance 0.1778)
			(thermal_gap 0.1778)
		)
		(pad "B22" thru_hole circle
			(at 11.34999 3.24993)
			(size 1.0668 1.0668)
			(drill 0.7112)
			(layers "*.Cu" "*.Mask")
			(remove_unused_layers no)
			(net "GND")
			(clearance 0.1778)
			(thermal_gap 0.1778)
		)
		(pad "B23" thru_hole circle
			(at 12.34948 1.24968)
			(size 1.0668 1.0668)
			(drill 0.7112)
			(layers "*.Cu" "*.Mask")
			(remove_unused_layers no)
			(net "P3E_CPU0_PE2_SS_C_TXP<2>")
			(clearance 0.1778)
			(thermal_gap 0.1778)
		)
		(pad "B24" thru_hole circle
			(at 13.35024 3.24993)
			(size 1.0668 1.0668)
			(drill 0.7112)
			(layers "*.Cu" "*.Mask")
			(remove_unused_layers no)
			(net "P3E_CPU0_PE2_SS_C_TXN<2>")
			(clearance 0.1778)
			(thermal_gap 0.1778)
		)
		(pad "B25" thru_hole circle
			(at 14.34973 1.24968)
			(size 1.0668 1.0668)
			(drill 0.7112)
			(layers "*.Cu" "*.Mask")
			(remove_unused_layers no)
			(net "GND")
			(clearance 0.1778)
			(thermal_gap 0.1778)
		)
		(pad "B26" thru_hole circle
			(at 15.35049 3.24993)
			(size 1.0668 1.0668)
			(drill 0.7112)
			(layers "*.Cu" "*.Mask")
			(remove_unused_layers no)
			(net "GND")
			(clearance 0.1778)
			(thermal_gap 0.1778)
		)
		(pad "B27" thru_hole circle
			(at 16.34998 1.24968)
			(size 1.0668 1.0668)
			(drill 0.7112)
			(layers "*.Cu" "*.Mask")
			(remove_unused_layers no)
			(net "P3E_CPU0_PE2_SS_C_TXP<3>")
			(clearance 0.1778)
			(thermal_gap 0.1778)
		)
		(pad "B28" thru_hole circle
			(at 17.34947 3.24993)
			(size 1.0668 1.0668)
			(drill 0.7112)
			(layers "*.Cu" "*.Mask")
			(remove_unused_layers no)
			(net "P3E_CPU0_PE2_SS_C_TXN<3>")
			(clearance 0.1778)
			(thermal_gap 0.1778)
		)
		(pad "B29" thru_hole circle
			(at 18.35023 1.24968)
			(size 1.0668 1.0668)
			(drill 0.7112)
			(layers "*.Cu" "*.Mask")
			(remove_unused_layers no)
			(net "GND")
			(clearance 0.1778)
			(thermal_gap 0.1778)
		)
		(pad "B30" thru_hole circle
			(at 19.34972 3.24993)
			(size 1.0668 1.0668)
			(drill 0.7112)
			(layers "*.Cu" "*.Mask")
			(remove_unused_layers no)
			(net "FM_PWRBRK_SLOT_N")
			(clearance 0.1778)
			(thermal_gap 0.1778)
		)
		(pad "B31" thru_hole circle
			(at 20.35048 1.24968)
			(size 1.0668 1.0668)
			(drill 0.7112)
			(layers "*.Cu" "*.Mask")
			(remove_unused_layers no)
			(net "PCIE_SLOT3_PRSNT2_2_N")
			(clearance 0.1778)
			(thermal_gap 0.1778)
		)
		(pad "B32" thru_hole circle
			(at 21.34997 3.24993)
			(size 1.0668 1.0668)
			(drill 0.7112)
			(layers "*.Cu" "*.Mask")
			(remove_unused_layers no)
			(net "GND")
			(clearance 0.1778)
			(thermal_gap 0.1778)
		)
		(pad "B33" thru_hole circle
			(at 22.34946 1.24968)
			(size 1.0668 1.0668)
			(drill 0.7112)
			(layers "*.Cu" "*.Mask")
			(remove_unused_layers no)
			(net "P3E_CPU0_PE2_SS_C_TXP<4>")
			(clearance 0.1778)
			(thermal_gap 0.1778)
		)
		(pad "B34" thru_hole circle
			(at 23.35022 3.24993)
			(size 1.0668 1.0668)
			(drill 0.7112)
			(layers "*.Cu" "*.Mask")
			(remove_unused_layers no)
			(net "P3E_CPU0_PE2_SS_C_TXN<4>")
			(clearance 0.1778)
			(thermal_gap 0.1778)
		)
		(pad "B35" thru_hole circle
			(at 24.34971 1.24968)
			(size 1.0668 1.0668)
			(drill 0.7112)
			(layers "*.Cu" "*.Mask")
			(remove_unused_layers no)
			(net "GND")
			(clearance 0.1778)
			(thermal_gap 0.1778)
		)
		(pad "B36" thru_hole circle
			(at 25.35047 3.24993)
			(size 1.0668 1.0668)
			(drill 0.7112)
			(layers "*.Cu" "*.Mask")
			(remove_unused_layers no)
			(net "GND")
			(clearance 0.1778)
			(thermal_gap 0.1778)
		)
		(pad "B37" thru_hole circle
			(at 26.34996 1.24968)
			(size 1.0668 1.0668)
			(drill 0.7112)
			(layers "*.Cu" "*.Mask")
			(remove_unused_layers no)
			(net "P3E_CPU0_PE2_SS_C_TXP<5>")
			(clearance 0.1778)
			(thermal_gap 0.1778)
		)
		(pad "B38" thru_hole circle
			(at 27.34945 3.24993)
			(size 1.0668 1.0668)
			(drill 0.7112)
			(layers "*.Cu" "*.Mask")
			(remove_unused_layers no)
			(net "P3E_CPU0_PE2_SS_C_TXN<5>")
			(clearance 0.1778)
			(thermal_gap 0.1778)
		)
		(pad "B39" thru_hole circle
			(at 28.35021 1.24968)
			(size 1.0668 1.0668)
			(drill 0.7112)
			(layers "*.Cu" "*.Mask")
			(remove_unused_layers no)
			(net "GND")
			(clearance 0.1778)
			(thermal_gap 0.1778)
		)
		(pad "B40" thru_hole circle
			(at 29.3497 3.24993)
			(size 1.0668 1.0668)
			(drill 0.7112)
			(layers "*.Cu" "*.Mask")
			(remove_unused_layers no)
			(net "GND")
			(clearance 0.1778)
			(thermal_gap 0.1778)
		)
		(pad "B41" thru_hole circle
			(at 30.35046 1.24968)
			(size 1.0668 1.0668)
			(drill 0.7112)
			(layers "*.Cu" "*.Mask")
			(remove_unused_layers no)
			(net "P3E_CPU0_PE2_SS_C_TXP<6>")
			(clearance 0.1778)
			(thermal_gap 0.1778)
		)
		(pad "B42" thru_hole circle
			(at 31.34995 3.24993)
			(size 1.0668 1.0668)
			(drill 0.7112)
			(layers "*.Cu" "*.Mask")
			(remove_unused_layers no)
			(net "P3E_CPU0_PE2_SS_C_TXN<6>")
			(clearance 0.1778)
			(thermal_gap 0.1778)
		)
		(pad "B43" thru_hole circle
			(at 32.34944 1.24968)
			(size 1.0668 1.0668)
			(drill 0.7112)
			(layers "*.Cu" "*.Mask")
			(remove_unused_layers no)
			(net "GND")
			(clearance 0.1778)
			(thermal_gap 0.1778)
		)
		(pad "B44" thru_hole circle
			(at 33.3502 3.24993)
			(size 1.0668 1.0668)
			(drill 0.7112)
			(layers "*.Cu" "*.Mask")
			(remove_unused_layers no)
			(net "GND")
			(clearance 0.1778)
			(thermal_gap 0.1778)
		)
		(pad "B45" thru_hole circle
			(at 34.34969 1.24968)
			(size 1.0668 1.0668)
			(drill 0.7112)
			(layers "*.Cu" "*.Mask")
			(remove_unused_layers no)
			(net "P3E_CPU0_PE2_SS_C_TXP<7>")
			(clearance 0.1778)
			(thermal_gap 0.1778)
		)
		(pad "B46" thru_hole circle
			(at 35.35045 3.24993)
			(size 1.0668 1.0668)
			(drill 0.7112)
			(layers "*.Cu" "*.Mask")
			(remove_unused_layers no)
			(net "P3E_CPU0_PE2_SS_C_TXN<7>")
			(clearance 0.1778)
			(thermal_gap 0.1778)
		)
		(pad "B47" thru_hole circle
			(at 36.34994 1.24968)
			(size 1.0668 1.0668)
			(drill 0.7112)
			(layers "*.Cu" "*.Mask")
			(remove_unused_layers no)
			(net "GND")
			(clearance 0.1778)
			(thermal_gap 0.1778)
		)
		(pad "B48" thru_hole circle
			(at 37.34943 3.24993)
			(size 1.0668 1.0668)
			(drill 0.7112)
			(layers "*.Cu" "*.Mask")
			(remove_unused_layers no)
			(net "PCIE_SLOT3_PRSNT2_3_N")
			(clearance 0.1778)
			(thermal_gap 0.1778)
		)
		(pad "B49" thru_hole circle
			(at 38.35019 1.24968)
			(size 1.0668 1.0668)
			(drill 0.7112)
			(layers "*.Cu" "*.Mask")
			(remove_unused_layers no)
			(net "GND")
			(clearance 0.1778)
			(thermal_gap 0.1778)
		)
		(pad "B50" thru_hole circle
			(at 39.34968 3.24993)
			(size 1.0668 1.0668)
			(drill 0.7112)
			(layers "*.Cu" "*.Mask")
			(remove_unused_layers no)
			(net "P3E_CPU0_PE2_SS_C_TXP<8>")
			(clearance 0.1778)
			(thermal_gap 0.1778)
		)
		(pad "B51" thru_hole circle
			(at 40.35044 1.24968)
			(size 1.0668 1.0668)
			(drill 0.7112)
			(layers "*.Cu" "*.Mask")
			(remove_unused_layers no)
			(net "P3E_CPU0_PE2_SS_C_TXN<8>")
			(clearance 0.1778)
			(thermal_gap 0.1778)
		)
		(pad "B52" thru_hole circle
			(at 41.34993 3.24993)
			(size 1.0668 1.0668)
			(drill 0.7112)
			(layers "*.Cu" "*.Mask")
			(remove_unused_layers no)
			(net "GND")
			(clearance 0.1778)
			(thermal_gap 0.1778)
		)
		(pad "B53" thru_hole circle
			(at 42.34942 1.24968)
			(size 1.0668 1.0668)
			(drill 0.7112)
			(layers "*.Cu" "*.Mask")
			(remove_unused_layers no)
			(net "GND")
			(clearance 0.1778)
			(thermal_gap 0.1778)
		)
		(pad "B54" thru_hole circle
			(at 43.35018 3.24993)
			(size 1.0668 1.0668)
			(drill 0.7112)
			(layers "*.Cu" "*.Mask")
			(remove_unused_layers no)
			(net "P3E_CPU0_PE2_SS_C_TXP<9>")
			(clearance 0.1778)
			(thermal_gap 0.1778)
		)
		(pad "B55" thru_hole circle
			(at 44.34967 1.24968)
			(size 1.0668 1.0668)
			(drill 0.7112)
			(layers "*.Cu" "*.Mask")
			(remove_unused_layers no)
			(net "P3E_CPU0_PE2_SS_C_TXN<9>")
			(clearance 0.1778)
			(thermal_gap 0.1778)
		)
		(pad "B56" thru_hole circle
			(at 45.35043 3.24993)
			(size 1.0668 1.0668)
			(drill 0.7112)
			(layers "*.Cu" "*.Mask")
			(remove_unused_layers no)
			(net "GND")
			(clearance 0.1778)
			(thermal_gap 0.1778)
		)
		(pad "B57" thru_hole circle
			(at 46.34992 1.24968)
			(size 1.0668 1.0668)
			(drill 0.7112)
			(layers "*.Cu" "*.Mask")
			(remove_unused_layers no)
			(net "GND")
			(clearance 0.1778)
			(thermal_gap 0.1778)
		)
		(pad "B58" thru_hole circle
			(at 47.34941 3.24993)
			(size 1.0668 1.0668)
			(drill 0.7112)
			(layers "*.Cu" "*.Mask")
			(remove_unused_layers no)
			(net "P3E_CPU0_PE2_SS_C_TXP<10>")
			(clearance 0.1778)
			(thermal_gap 0.1778)
		)
		(pad "B59" thru_hole circle
			(at 48.35017 1.24968)
			(size 1.0668 1.0668)
			(drill 0.7112)
			(layers "*.Cu" "*.Mask")
			(remove_unused_layers no)
			(net "P3E_CPU0_PE2_SS_C_TXN<10>")
			(clearance 0.1778)
			(thermal_gap 0.1778)
		)
		(pad "B60" thru_hole circle
			(at 49.34966 3.24993)
			(size 1.0668 1.0668)
			(drill 0.7112)
			(layers "*.Cu" "*.Mask")
			(remove_unused_layers no)
			(net "GND")
			(clearance 0.1778)
			(thermal_gap 0.1778)
		)
		(pad "B61" thru_hole circle
			(at 50.35042 1.24968)
			(size 1.0668 1.0668)
			(drill 0.7112)
			(layers "*.Cu" "*.Mask")
			(remove_unused_layers no)
			(net "GND")
			(clearance 0.1778)
			(thermal_gap 0.1778)
		)
		(pad "B62" thru_hole circle
			(at 51.34991 3.24993)
			(size 1.0668 1.0668)
			(drill 0.7112)
			(layers "*.Cu" "*.Mask")
			(remove_unused_layers no)
			(net "P3E_CPU0_PE2_SS_C_TXP<11>")
			(clearance 0.1778)
			(thermal_gap 0.1778)
		)
		(pad "B63" thru_hole circle
			(at 52.3494 1.24968)
			(size 1.0668 1.0668)
			(drill 0.7112)
			(layers "*.Cu" "*.Mask")
			(remove_unused_layers no)
			(net "P3E_CPU0_PE2_SS_C_TXN<11>")
			(clearance 0.1778)
			(thermal_gap 0.1778)
		)
		(pad "B64" thru_hole circle
			(at 53.35016 3.24993)
			(size 1.0668 1.0668)
			(drill 0.7112)
			(layers "*.Cu" "*.Mask")
			(remove_unused_layers no)
			(net "GND")
			(clearance 0.1778)
			(thermal_gap 0.1778)
		)
		(pad "B65" thru_hole circle
			(at 54.34965 1.24968)
			(size 1.0668 1.0668)
			(drill 0.7112)
			(layers "*.Cu" "*.Mask")
			(remove_unused_layers no)
			(net "GND")
			(clearance 0.1778)
			(thermal_gap 0.1778)
		)
		(pad "B66" thru_hole circle
			(at 55.35041 3.24993)
			(size 1.0668 1.0668)
			(drill 0.7112)
			(layers "*.Cu" "*.Mask")
			(remove_unused_layers no)
			(net "P3E_CPU0_PE2_SS_C_TXP<12>")
			(clearance 0.1778)
			(thermal_gap 0.1778)
		)
		(pad "B67" thru_hole circle
			(at 56.3499 1.24968)
			(size 1.0668 1.0668)
			(drill 0.7112)
			(layers "*.Cu" "*.Mask")
			(remove_unused_layers no)
			(net "P3E_CPU0_PE2_SS_C_TXN<12>")
			(clearance 0.1778)
			(thermal_gap 0.1778)
		)
	)
)
